(kicad_pcb
	(version 20241229)
	(generator "pcbnew")
	(generator_version "9.0")
	(general
		(thickness 1.6)
		(legacy_teardrops no)
	)
	(paper "A4")
	(title_block
		(title "environment-sensor")
		(comment 1 "footprints 30-36 of 109")
	)
	(layers
		(0 "F.Cu" signal)
		(4 "In1.Cu" signal)
		(6 "In2.Cu" signal)
		(2 "B.Cu" signal)
		(9 "F.Adhes" user "F.Adhesive")
		(11 "B.Adhes" user "B.Adhesive")
		(13 "F.Paste" user)
		(15 "B.Paste" user)
		(5 "F.SilkS" user "F.Silkscreen")
		(7 "B.SilkS" user "B.Silkscreen")
		(1 "F.Mask" user)
		(3 "B.Mask" user)
		(17 "Dwgs.User" user "User.Drawings")
		(19 "Cmts.User" user "User.Comments")
		(21 "Eco1.User" user "User.Eco1")
		(23 "Eco2.User" user "User.Eco2")
		(25 "Edge.Cuts" user)
		(27 "Margin" user)
		(31 "F.CrtYd" user "F.Courtyard")
		(29 "B.CrtYd" user "B.Courtyard")
		(35 "F.Fab" user)
		(33 "B.Fab" user)
	)
	(footprint "antmicro-footprints:R_0402_1005Metric"
		(layer "F.Cu")
		(at 187.35 138.4 90)
		(descr "Resistor SMD 0402")
		(tags "resistor SMD 0402")
		(property "Reference" "R16"
			(at 20.35 -1.65 90)
			(layer "B.SilkS")
			(effects
				(font
					(size 0.7 0.7)
					(thickness 0.15)
				)
				(justify left bottom mirror)
			)
		)
		(property "Value" "R_0R_0402"
			(at -1.011843 1.772047 90)
			(layer "F.Fab")
			(effects
				(font
					(size 0.7 0.7)
					(thickness 0.15)
				)
				(justify left bottom)
			)
		)
		(property "Description" "SMD Chip Resistor, Jumper, 0 ohm, 100 mW, 0402 [1005 Metric], Thick Film, General Purpose"
			(at 0 0 90)
			(layer "F.Fab")
			(hide yes)
			(effects
				(font
					(size 1.27 1.27)
					(thickness 0.15)
				)
			)
		)
		(property "Author" "Antmicro"
			(at 325.75 -48.95 0)
			(layer "F.Fab")
			(hide yes)
			(effects
				(font
					(size 1 1)
					(thickness 0.15)
				)
			)
		)
		(property "Current" "1A"
			(at 325.75 -48.95 0)
			(layer "F.Fab")
			(hide yes)
			(effects
				(font
					(size 1 1)
					(thickness 0.15)
				)
			)
		)
		(property "License" "Apache-2.0"
			(at 325.75 -48.95 0)
			(layer "F.Fab")
			(hide yes)
			(effects
				(font
					(size 1 1)
					(thickness 0.15)
				)
			)
		)
		(property "MPN" "ERJ2GE0R00X"
			(at 325.75 -48.95 0)
			(layer "F.Fab")
			(hide yes)
			(effects
				(font
					(size 1 1)
					(thickness 0.15)
				)
			)
		)
		(property "Manufacturer" "Panasonic"
			(at 325.75 -48.95 0)
			(layer "F.Fab")
			(hide yes)
			(effects
				(font
					(size 1 1)
					(thickness 0.15)
				)
			)
		)
		(property "Public" "False"
			(at 325.75 -48.95 0)
			(layer "F.Fab")
			(hide yes)
			(effects
				(font
					(size 1 1)
					(thickness 0.15)
				)
			)
		)
		(property "Tolerance" ""
			(at 325.75 -48.95 0)
			(layer "F.Fab")
			(hide yes)
			(effects
				(font
					(size 1 1)
					(thickness 0.15)
				)
			)
		)
		(property "Val" "0R"
			(at 325.75 -48.95 0)
			(layer "F.Fab")
			(hide yes)
			(effects
				(font
					(size 1 1)
					(thickness 0.15)
				)
			)
		)
		(sheetfile "environment-sensor.kicad_sch")
		(attr smd exclude_from_pos_files exclude_from_bom dnp)
		(fp_rect
			(start -0.925 -0.47)
			(end 0.925 0.47)
			(stroke
				(width 0.05)
				(type default)
			)
			(fill no)
			(layer "F.CrtYd")
		)
		(fp_rect
			(start -0.5 -0.25)
			(end 0.5 0.25)
			(stroke
				(width 0.15)
				(type solid)
			)
			(fill no)
			(layer "F.Fab")
		)
		(pad "1" smd roundrect
			(at -0.48 0 90)
			(size 0.59 0.64)
			(layers "F.Cu" "F.Mask" "F.Paste")
			(roundrect_rratio 0.25)
			(net 45 "Net-(U1-RXD)")
			(pintype "passive")
		)
		(pad "2" smd roundrect
			(at 0.48 0 90)
			(size 0.59 0.64)
			(layers "F.Cu" "F.Mask" "F.Paste")
			(roundrect_rratio 0.25)
			(net 16 "LPUART_1_STM_RX")
			(pintype "passive")
		)
	)
	(footprint "antmicro-footprints:TP_SMD_1mm"
		(layer "F.Cu")
		(at 199.404 127.566)
		(property "Reference" "TP12"
			(at 0 -0.731898 0)
			(layer "F.SilkS")
			(hide yes)
			(effects
				(font
					(size 0.7 0.7)
					(thickness 0.15)
				)
				(justify left bottom)
			)
		)
		(property "Value" "TP_1mm_SMD"
			(at 0 1.4 0)
			(layer "F.Fab")
			(effects
				(font
					(size 0.7 0.7)
					(thickness 0.15)
				)
				(justify left bottom)
			)
		)
		(property "Description" "Test point 1mm SMD"
			(at 0 0 0)
			(layer "F.Fab")
			(hide yes)
			(effects
				(font
					(size 1.27 1.27)
					(thickness 0.15)
				)
			)
		)
		(property "Author" "Antmicro"
			(at 0 0 0)
			(layer "F.Fab")
			(hide yes)
			(effects
				(font
					(size 1 1)
					(thickness 0.15)
				)
			)
		)
		(property "License" "Apache-2.0"
			(at 0 0 0)
			(layer "F.Fab")
			(hide yes)
			(effects
				(font
					(size 1 1)
					(thickness 0.15)
				)
			)
		)
		(property "MPN" ""
			(at 0 0 0)
			(layer "F.Fab")
			(hide yes)
			(effects
				(font
					(size 1 1)
					(thickness 0.15)
				)
			)
		)
		(property "Manufacturer" ""
			(at 0 0 0)
			(layer "F.Fab")
			(hide yes)
			(effects
				(font
					(size 1 1)
					(thickness 0.15)
				)
			)
		)
		(property "Public" "False"
			(at 0 0 0)
			(layer "F.Fab")
			(hide yes)
			(effects
				(font
					(size 1 1)
					(thickness 0.15)
				)
			)
		)
		(sheetfile "environment-sensor.kicad_sch")
		(attr exclude_from_pos_files)
		(pad "1" smd circle
			(at 0 0)
			(size 1 1)
			(layers "F.Cu" "F.Mask")
			(net 8 "I2C_1_SCL")
			(pinfunction "1")
			(pintype "passive")
		)
	)
	(footprint "antmicro-footprints:C_0402_1005Metric"
		(layer "F.Cu")
		(at 175.05 133.6 90)
		(descr "Capacitor SMD 0402")
		(tags "capacitor SMD 0402")
		(property "Reference" "C10"
			(at 0.85 -0.1 45)
			(layer "F.SilkS")
			(effects
				(font
					(size 0.7 0.7)
					(thickness 0.15)
				)
				(justify left bottom)
			)
		)
		(property "Value" "C_4u7_0402"
			(at 0 1.4 90)
			(layer "F.Fab")
			(effects
				(font
					(size 0.7 0.7)
					(thickness 0.15)
				)
				(justify left bottom)
			)
		)
		(property "Description" "SMD Multilayer Ceramic Capacitor, 4.7 µF, 10 V, 0402 [1005 Metric], ± 20%, X5R, GRM Series"
			(at 0 0 90)
			(layer "F.Fab")
			(hide yes)
			(effects
				(font
					(size 1.27 1.27)
					(thickness 0.15)
				)
			)
		)
		(property "Author" "Antmicro"
			(at 308.65 -41.45 0)
			(layer "F.Fab")
			(hide yes)
			(effects
				(font
					(size 1 1)
					(thickness 0.15)
				)
			)
		)
		(property "Dielectric" ""
			(at 308.65 -41.45 0)
			(layer "F.Fab")
			(hide yes)
			(effects
				(font
					(size 1 1)
					(thickness 0.15)
				)
			)
		)
		(property "License" "Apache-2.0"
			(at 308.65 -41.45 0)
			(layer "F.Fab")
			(hide yes)
			(effects
				(font
					(size 1 1)
					(thickness 0.15)
				)
			)
		)
		(property "MPN" "GRM155R61A475MEAAD"
			(at 308.65 -41.45 0)
			(layer "F.Fab")
			(hide yes)
			(effects
				(font
					(size 1 1)
					(thickness 0.15)
				)
			)
		)
		(property "Manufacturer" "Murata"
			(at 308.65 -41.45 0)
			(layer "F.Fab")
			(hide yes)
			(effects
				(font
					(size 1 1)
					(thickness 0.15)
				)
			)
		)
		(property "Public" "False"
			(at 308.65 -41.45 0)
			(layer "F.Fab")
			(hide yes)
			(effects
				(font
					(size 1 1)
					(thickness 0.15)
				)
			)
		)
		(property "Val" "4u7"
			(at 308.65 -41.45 0)
			(layer "F.Fab")
			(hide yes)
			(effects
				(font
					(size 1 1)
					(thickness 0.15)
				)
			)
		)
		(property "Voltage" ""
			(at 308.65 -41.45 0)
			(layer "F.Fab")
			(hide yes)
			(effects
				(font
					(size 1 1)
					(thickness 0.15)
				)
			)
		)
		(sheetfile "environment-sensor.kicad_sch")
		(attr smd)
		(fp_rect
			(start -0.925 -0.47)
			(end 0.925 0.47)
			(stroke
				(width 0.05)
				(type default)
			)
			(fill no)
			(layer "F.CrtYd")
		)
		(fp_line
			(start 0.504 -0.25)
			(end 0.504 0.248)
			(stroke
				(width 0.15)
				(type solid)
			)
			(layer "F.Fab")
		)
		(fp_line
			(start -0.494 -0.25)
			(end 0.504 -0.25)
			(stroke
				(width 0.15)
				(type solid)
			)
			(layer "F.Fab")
		)
		(fp_line
			(start 0.504 0.248)
			(end -0.494 0.248)
			(stroke
				(width 0.15)
				(type solid)
			)
			(layer "F.Fab")
		)
		(fp_line
			(start -0.494 0.248)
			(end -0.494 -0.25)
			(stroke
				(width 0.15)
				(type solid)
			)
			(layer "F.Fab")
		)
		(pad "1" smd roundrect
			(at -0.48 0 90)
			(size 0.59 0.64)
			(layers "F.Cu" "F.Mask" "F.Paste")
			(roundrect_rratio 0.25)
			(net 1 "GND")
			(pintype "passive")
		)
		(pad "2" smd roundrect
			(at 0.48 0 90)
			(size 0.59 0.64)
			(layers "F.Cu" "F.Mask" "F.Paste")
			(roundrect_rratio 0.25)
			(net 2 "+3V3")
			(pintype "passive")
		)
	)
	(footprint "antmicro-footprints:C_0402_1005Metric"
		(layer "F.Cu")
		(at 205.15 119.835 -90)
		(descr "Capacitor SMD 0402")
		(tags "capacitor SMD 0402")
		(property "Reference" "C26"
			(at -0.935 -1.35 90)
			(layer "F.SilkS")
			(effects
				(font
					(size 0.7 0.7)
					(thickness 0.15)
				)
				(justify right bottom)
			)
		)
		(property "Value" "C_100n_0402"
			(at 0 1.4 90)
			(layer "F.Fab")
			(effects
				(font
					(size 0.7 0.7)
					(thickness 0.15)
				)
				(justify right bottom)
			)
		)
		(property "Description" "SMD Multilayer Ceramic Capacitor, 0.1 µF, 50 V, 0402 [1005 Metric], ± 10%, X5R, GRM Series"
			(at 0 0 270)
			(layer "F.Fab")
			(hide yes)
			(effects
				(font
					(size 1.27 1.27)
					(thickness 0.15)
				)
			)
		)
		(property "Author" "Antmicro"
			(at 85.315 324.985 0)
			(layer "F.Fab")
			(hide yes)
			(effects
				(font
					(size 1 1)
					(thickness 0.15)
				)
			)
		)
		(property "Dielectric" "X5R"
			(at 85.315 324.985 0)
			(layer "F.Fab")
			(hide yes)
			(effects
				(font
					(size 1 1)
					(thickness 0.15)
				)
			)
		)
		(property "License" "Apache-2.0"
			(at 85.315 324.985 0)
			(layer "F.Fab")
			(hide yes)
			(effects
				(font
					(size 1 1)
					(thickness 0.15)
				)
			)
		)
		(property "MPN" "GRM155R61H104KE14D"
			(at 85.315 324.985 0)
			(layer "F.Fab")
			(hide yes)
			(effects
				(font
					(size 1 1)
					(thickness 0.15)
				)
			)
		)
		(property "Manufacturer" "Murata"
			(at 85.315 324.985 0)
			(layer "F.Fab")
			(hide yes)
			(effects
				(font
					(size 1 1)
					(thickness 0.15)
				)
			)
		)
		(property "Public" "False"
			(at 85.315 324.985 0)
			(layer "F.Fab")
			(hide yes)
			(effects
				(font
					(size 1 1)
					(thickness 0.15)
				)
			)
		)
		(property "Val" "100n"
			(at 85.315 324.985 0)
			(layer "F.Fab")
			(hide yes)
			(effects
				(font
					(size 1 1)
					(thickness 0.15)
				)
			)
		)
		(property "Voltage" "50V"
			(at 85.315 324.985 0)
			(layer "F.Fab")
			(hide yes)
			(effects
				(font
					(size 1 1)
					(thickness 0.15)
				)
			)
		)
		(sheetfile "environment-sensor.kicad_sch")
		(attr smd)
		(fp_rect
			(start -0.925 -0.47)
			(end 0.925 0.47)
			(stroke
				(width 0.05)
				(type default)
			)
			(fill no)
			(layer "F.CrtYd")
		)
		(fp_line
			(start -0.494 0.248)
			(end -0.494 -0.25)
			(stroke
				(width 0.15)
				(type solid)
			)
			(layer "F.Fab")
		)
		(fp_line
			(start 0.504 0.248)
			(end -0.494 0.248)
			(stroke
				(width 0.15)
				(type solid)
			)
			(layer "F.Fab")
		)
		(fp_line
			(start -0.494 -0.25)
			(end 0.504 -0.25)
			(stroke
				(width 0.15)
				(type solid)
			)
			(layer "F.Fab")
		)
		(fp_line
			(start 0.504 -0.25)
			(end 0.504 0.248)
			(stroke
				(width 0.15)
				(type solid)
			)
			(layer "F.Fab")
		)
		(pad "1" smd roundrect
			(at -0.48 0 270)
			(size 0.59 0.64)
			(layers "F.Cu" "F.Mask" "F.Paste")
			(roundrect_rratio 0.25)
			(net 2 "+3V3")
			(pintype "passive")
		)
		(pad "2" smd roundrect
			(at 0.48 0 270)
			(size 0.59 0.64)
			(layers "F.Cu" "F.Mask" "F.Paste")
			(roundrect_rratio 0.25)
			(net 1 "GND")
			(pintype "passive")
		)
	)
	(footprint "antmicro-footprints:C_0402_1005Metric"
		(layer "F.Cu")
		(at 174.249 123.7 90)
		(descr "Capacitor SMD 0402")
		(tags "capacitor SMD 0402")
		(property "Reference" "C1"
			(at -2.373 0.344 90)
			(layer "F.SilkS")
			(effects
				(font
					(size 0.7 0.7)
					(thickness 0.15)
				)
				(justify left bottom)
			)
		)
		(property "Value" "C_4u7_0402"
			(at 0 1.4 90)
			(layer "F.Fab")
			(effects
				(font
					(size 0.7 0.7)
					(thickness 0.15)
				)
				(justify left bottom)
			)
		)
		(property "Description" "SMD Multilayer Ceramic Capacitor, 4.7 µF, 10 V, 0402 [1005 Metric], ± 20%, X5R, GRM Series"
			(at 0 0 90)
			(layer "F.Fab")
			(hide yes)
			(effects
				(font
					(size 1.27 1.27)
					(thickness 0.15)
				)
			)
		)
		(property "Author" "Antmicro"
			(at 297.949 -50.549 0)
			(layer "F.Fab")
			(hide yes)
			(effects
				(font
					(size 1 1)
					(thickness 0.15)
				)
			)
		)
		(property "Dielectric" ""
			(at 297.949 -50.549 0)
			(layer "F.Fab")
			(hide yes)
			(effects
				(font
					(size 1 1)
					(thickness 0.15)
				)
			)
		)
		(property "License" "Apache-2.0"
			(at 297.949 -50.549 0)
			(layer "F.Fab")
			(hide yes)
			(effects
				(font
					(size 1 1)
					(thickness 0.15)
				)
			)
		)
		(property "MPN" "GRM155R61A475MEAAD"
			(at 297.949 -50.549 0)
			(layer "F.Fab")
			(hide yes)
			(effects
				(font
					(size 1 1)
					(thickness 0.15)
				)
			)
		)
		(property "Manufacturer" "Murata"
			(at 297.949 -50.549 0)
			(layer "F.Fab")
			(hide yes)
			(effects
				(font
					(size 1 1)
					(thickness 0.15)
				)
			)
		)
		(property "Public" "False"
			(at 297.949 -50.549 0)
			(layer "F.Fab")
			(hide yes)
			(effects
				(font
					(size 1 1)
					(thickness 0.15)
				)
			)
		)
		(property "Val" "4u7"
			(at 297.949 -50.549 0)
			(layer "F.Fab")
			(hide yes)
			(effects
				(font
					(size 1 1)
					(thickness 0.15)
				)
			)
		)
		(property "Voltage" ""
			(at 297.949 -50.549 0)
			(layer "F.Fab")
			(hide yes)
			(effects
				(font
					(size 1 1)
					(thickness 0.15)
				)
			)
		)
		(sheetfile "environment-sensor.kicad_sch")
		(attr smd)
		(fp_rect
			(start -0.925 -0.47)
			(end 0.925 0.47)
			(stroke
				(width 0.05)
				(type default)
			)
			(fill no)
			(layer "F.CrtYd")
		)
		(fp_line
			(start 0.504 -0.25)
			(end 0.504 0.248)
			(stroke
				(width 0.15)
				(type solid)
			)
			(layer "F.Fab")
		)
		(fp_line
			(start -0.494 -0.25)
			(end 0.504 -0.25)
			(stroke
				(width 0.15)
				(type solid)
			)
			(layer "F.Fab")
		)
		(fp_line
			(start 0.504 0.248)
			(end -0.494 0.248)
			(stroke
				(width 0.15)
				(type solid)
			)
			(layer "F.Fab")
		)
		(fp_line
			(start -0.494 0.248)
			(end -0.494 -0.25)
			(stroke
				(width 0.15)
				(type solid)
			)
			(layer "F.Fab")
		)
		(pad "1" smd roundrect
			(at -0.48 0 90)
			(size 0.59 0.64)
			(layers "F.Cu" "F.Mask" "F.Paste")
			(roundrect_rratio 0.25)
			(net 1 "GND")
			(pintype "passive")
		)
		(pad "2" smd roundrect
			(at 0.48 0 90)
			(size 0.59 0.64)
			(layers "F.Cu" "F.Mask" "F.Paste")
			(roundrect_rratio 0.25)
			(net 26 "+5V")
			(pintype "passive")
		)
	)
	(footprint "antmicro-footprints:R_0402_1005Metric"
		(layer "F.Cu")
		(at 184.05 138.4 90)
		(descr "Resistor SMD 0402")
		(tags "resistor SMD 0402")
		(property "Reference" "R15"
			(at 20.35 -1.1 90)
			(layer "B.SilkS")
			(effects
				(font
					(size 0.7 0.7)
					(thickness 0.15)
				)
				(justify left bottom mirror)
			)
		)
		(property "Value" "R_0R_0402"
			(at -1.011843 1.772047 90)
			(layer "F.Fab")
			(effects
				(font
					(size 0.7 0.7)
					(thickness 0.15)
				)
				(justify left bottom)
			)
		)
		(property "Description" "SMD Chip Resistor, Jumper, 0 ohm, 100 mW, 0402 [1005 Metric], Thick Film, General Purpose"
			(at 0 0 90)
			(layer "F.Fab")
			(hide yes)
			(effects
				(font
					(size 1.27 1.27)
					(thickness 0.15)
				)
			)
		)
		(property "Author" "Antmicro"
			(at 322.45 -45.65 0)
			(layer "F.Fab")
			(hide yes)
			(effects
				(font
					(size 1 1)
					(thickness 0.15)
				)
			)
		)
		(property "Current" "1A"
			(at 322.45 -45.65 0)
			(layer "F.Fab")
			(hide yes)
			(effects
				(font
					(size 1 1)
					(thickness 0.15)
				)
			)
		)
		(property "License" "Apache-2.0"
			(at 322.45 -45.65 0)
			(layer "F.Fab")
			(hide yes)
			(effects
				(font
					(size 1 1)
					(thickness 0.15)
				)
			)
		)
		(property "MPN" "ERJ2GE0R00X"
			(at 322.45 -45.65 0)
			(layer "F.Fab")
			(hide yes)
			(effects
				(font
					(size 1 1)
					(thickness 0.15)
				)
			)
		)
		(property "Manufacturer" "Panasonic"
			(at 322.45 -45.65 0)
			(layer "F.Fab")
			(hide yes)
			(effects
				(font
					(size 1 1)
					(thickness 0.15)
				)
			)
		)
		(property "Public" "False"
			(at 322.45 -45.65 0)
			(layer "F.Fab")
			(hide yes)
			(effects
				(font
					(size 1 1)
					(thickness 0.15)
				)
			)
		)
		(property "Tolerance" ""
			(at 322.45 -45.65 0)
			(layer "F.Fab")
			(hide yes)
			(effects
				(font
					(size 1 1)
					(thickness 0.15)
				)
			)
		)
		(property "Val" "0R"
			(at 322.45 -45.65 0)
			(layer "F.Fab")
			(hide yes)
			(effects
				(font
					(size 1 1)
					(thickness 0.15)
				)
			)
		)
		(sheetfile "environment-sensor.kicad_sch")
		(attr smd exclude_from_pos_files exclude_from_bom dnp)
		(fp_rect
			(start -0.925 -0.47)
			(end 0.925 0.47)
			(stroke
				(width 0.05)
				(type default)
			)
			(fill no)
			(layer "F.CrtYd")
		)
		(fp_rect
			(start -0.5 -0.25)
			(end 0.5 0.25)
			(stroke
				(width 0.15)
				(type solid)
			)
			(fill no)
			(layer "F.Fab")
		)
		(pad "1" smd roundrect
			(at -0.48 0 90)
			(size 0.59 0.64)
			(layers "F.Cu" "F.Mask" "F.Paste")
			(roundrect_rratio 0.25)
			(net 44 "Net-(U1-TXD)")
			(pintype "passive")
		)
		(pad "2" smd roundrect
			(at 0.48 0 90)
			(size 0.59 0.64)
			(layers "F.Cu" "F.Mask" "F.Paste")
			(roundrect_rratio 0.25)
			(net 17 "LPUART_1_STM_TX")
			(pintype "passive")
		)
	)
	(footprint "antmicro-footprints:R_0402_1005Metric"
		(layer "F.Cu")
		(at 203.75 117.835 90)
		(descr "Resistor SMD 0402")
		(tags "resistor SMD 0402")
		(property "Reference" "R35"
			(at -2.465 -3.55 180)
			(layer "F.SilkS")
			(effects
				(font
					(size 0.7 0.7)
					(thickness 0.15)
				)
				(justify left bottom)
			)
		)
		(property "Value" "R_100k_0402"
			(at 0 1.4 90)
			(layer "F.Fab")
			(effects
				(font
					(size 0.7 0.7)
					(thickness 0.15)
				)
				(justify left bottom)
			)
		)
		(property "Description" "SMD Chip Resistor, 100 kohm, ± 1%, 62.5 mW, 0402 [1005 Metric], Thick Film, General Purpose"
			(at 0 0 90)
			(layer "F.Fab")
			(hide yes)
			(effects
				(font
					(size 1.27 1.27)
					(thickness 0.15)
				)
			)
		)
		(property "Author" "Antmicro"
			(at 321.585 -85.915 0)
			(layer "F.Fab")
			(hide yes)
			(effects
				(font
					(size 1 1)
					(thickness 0.15)
				)
			)
		)
		(property "License" "Apache-2.0"
			(at 321.585 -85.915 0)
			(layer "F.Fab")
			(hide yes)
			(effects
				(font
					(size 1 1)
					(thickness 0.15)
				)
			)
		)
		(property "MPN" "CR0402-FX-1003GLF"
			(at 321.585 -85.915 0)
			(layer "F.Fab")
			(hide yes)
			(effects
				(font
					(size 1 1)
					(thickness 0.15)
				)
			)
		)
		(property "Manufacturer" "Bourns"
			(at 321.585 -85.915 0)
			(layer "F.Fab")
			(hide yes)
			(effects
				(font
					(size 1 1)
					(thickness 0.15)
				)
			)
		)
		(property "Public" "False"
			(at 321.585 -85.915 0)
			(layer "F.Fab")
			(hide yes)
			(effects
				(font
					(size 1 1)
					(thickness 0.15)
				)
			)
		)
		(property "Tolerance" "1%"
			(at 321.585 -85.915 0)
			(layer "F.Fab")
			(hide yes)
			(effects
				(font
					(size 1 1)
					(thickness 0.15)
				)
			)
		)
		(property "Val" "100k"
			(at 321.585 -85.915 0)
			(layer "F.Fab")
			(hide yes)
			(effects
				(font
					(size 1 1)
					(thickness 0.15)
				)
			)
		)
		(sheetfile "environment-sensor.kicad_sch")
		(attr smd exclude_from_pos_files exclude_from_bom dnp)
		(fp_rect
			(start -0.925 -0.47)
			(end 0.925 0.47)
			(stroke
				(width 0.05)
				(type default)
			)
			(fill no)
			(layer "F.CrtYd")
		)
		(fp_rect
			(start -0.5 -0.25)
			(end 0.5 0.25)
			(stroke
				(width 0.15)
				(type solid)
			)
			(fill no)
			(layer "F.Fab")
		)
		(pad "1" smd roundrect
			(at -0.48 0 90)
			(size 0.59 0.64)
			(layers "F.Cu" "F.Mask" "F.Paste")
			(roundrect_rratio 0.25)
			(net 2 "+3V3")
			(pintype "passive")
		)
		(pad "2" smd roundrect
			(at 0.48 0 90)
			(size 0.59 0.64)
			(layers "F.Cu" "F.Mask" "F.Paste")
			(roundrect_rratio 0.25)
			(net 53 "Net-(U6-SDO)")
			(pintype "passive")
		)
	)
)
